# BARRELEYE_G2-FPDB_POST-EVT-HW-EBOM-X00_20161123-add_2nd_source_X08-20161215-Final-b.xls — TLA-FPDB (bom)
| FOXCONN TECHNOLOGY GROUP |  |  |  |  |  |  |  |  |  |
| BILL OF MATERIAL |  |  |  |  |  |  |  |  |  |
| AA P/N | 1A42G4V00-600-G | CUSTOMER | <name> | Customer P/N |  | Product Code |  |  |  |
| PWA P/N |  | PWA DESCRIPTION | 風扇及電源分配板,ASSY,FPDB BOARD,G,BARRELEYE G2,RACKSPACE |  |  | PWA REV |  | Prepared By SE |  |
| Item | FOXCONN P/N | Customer P/N | Part Description | Manufacturer  Full Name | Manufacturer  Part Number | Qty | RoHS Status | Location | Remark |
| 1 | 7J-004-938 |  | L6 LABEL ( 12.7*11.1mm) | FOXCONN / EPD1 | 7J-004-938 | 1 | G |  | ID label for two boards. FPDB AA P/N: 1A42G4V00-600-G |
